# BASEBOARD_FAB2 (Tioga Pass) — schematic netlist excerpt (pin names and nets, part order shuffled) for the footprints in the layout excerpt that follows; sources: Cadence DE-HDL packaged netlist, KiCad conversion of Wiwynn_Tioga_Pass_MB.brd

C3P48  CAP_A  0.1UF 16V 10% X7R  pkg 0402V  page 192 : A = P3V3_STBY ; B = GND
C7M3  CAP  10UF 4V 20% X6S  pkg 0603LF  page 234 : A = PVPP_KLM ; B = GND
R32W9  RES  10.0K 1% CHIP  pkg 0402  page 185 : A = PD_SMB_M2_EN ; B = GND

(kicad_pcb
	(version 20260206)
	(generator "pcbnew")
	(generator_version "10.0")
	(general
		(thickness 1.6)
		(legacy_teardrops no)
	)
	(paper "A4")
	(title_block
		(title "Wiwynn_Tioga_Pass_MB.brd")
		(comment 1 "Tioga Pass / footprints 4209-4211 of 4770")
	)
	(layers
		(0 "F.Cu" signal "TOP")
		(4 "In1.Cu" signal "L2GND")
		(6 "In2.Cu" signal "L3")
		(8 "In3.Cu" signal "L4GND")
		(10 "In4.Cu" signal "L5")
		(12 "In5.Cu" signal "L6GND")
		(14 "In6.Cu" signal "L7VCC")
		(16 "In7.Cu" signal "L8VCC")
		(18 "In8.Cu" signal "L9GND")
		(20 "In9.Cu" signal "L10")
		(22 "In10.Cu" signal "L11GND")
		(24 "In11.Cu" signal "L12")
		(26 "In12.Cu" signal "L13GND")
		(2 "B.Cu" signal "BOTTOM")
		(9 "F.Adhes" user "F.Adhesive")
		(11 "B.Adhes" user "B.Adhesive")
		(13 "F.Paste" user "Package Geometry/Pastemask Top")
		(15 "B.Paste" user "Package Geometry/Pastemask Bottom")
		(5 "F.SilkS" user "Ref Des/Silkscreen Top")
		(7 "B.SilkS" user "Ref Des/Silkscreen Bottom")
		(1 "F.Mask" user "Board Geometry/Soldermask Top")
		(3 "B.Mask" user "Board Geometry/Soldermask Bottom")
		(17 "Dwgs.User" user "User.Drawings")
		(19 "Cmts.User" user "User.Comments")
		(21 "Eco1.User" user "User.Eco1")
		(23 "Eco2.User" user "User.Eco2")
		(25 "Edge.Cuts" user "Board Geometry/Outline")
		(27 "Margin" user)
		(31 "F.CrtYd" user "Package Geometry/Place Bound Top")
		(29 "B.CrtYd" user "Package Geometry/Place Bound Bottom")
		(35 "F.Fab" user "Ref Des/Assembly Top")
		(33 "B.Fab" user "Ref Des/Assembly Bottom")
	)
	(footprint ""
		(layer "B.Cu")
		(at 387.604 -16.383 90)
		(property "Reference" "R32W9"
			(at 0.8382 -0.67818 90)
			(unlocked yes)
			(layer "B.SilkS")
			(effects
				(font
					(size 0.4064 0.254)
					(thickness 0.1524)
				)
				(justify left mirror)
			)
		)
		(property "Value" ""
			(at 0 0 90)
			(layer "B.Fab")
			(effects
				(font
					(size 1.27 1.27)
				)
				(justify mirror)
			)
		)
		(duplicate_pad_numbers_are_jumpers no)
		(fp_poly
			(pts
				(xy 0.2794 -0.1016) (xy -0.2794 -0.1016) (xy -0.2794 0.9906) (xy 0.2794 0.9906)
			)
			(stroke
				(width 0)
				(type default)
			)
			(fill no)
			(layer "B.CrtYd")
		)
		(fp_line
			(start 0.2794 -0.1016)
			(end 0.2794 0.9906)
			(stroke
				(width 0.1)
				(type default)
			)
			(layer "B.Fab")
		)
		(fp_line
			(start -0.2794 -0.1016)
			(end 0.2794 -0.1016)
			(stroke
				(width 0.1)
				(type default)
			)
			(layer "B.Fab")
		)
		(fp_line
			(start 0.2794 0.9906)
			(end -0.2794 0.9906)
			(stroke
				(width 0.1)
				(type default)
			)
			(layer "B.Fab")
		)
		(fp_line
			(start -0.2794 0.9906)
			(end -0.2794 -0.1016)
			(stroke
				(width 0.1)
				(type default)
			)
			(layer "B.Fab")
		)
		(pad "1" smd rect
			(at 0 0 270)
			(size 0.508 0.508)
			(layers "B.Cu" "B.Mask" "B.Paste")
			(net "PD_SMB_M2_EN")
		)
		(pad "2" smd rect
			(at 0 0.889 270)
			(size 0.508 0.508)
			(layers "B.Cu" "B.Mask" "B.Paste")
			(net "GND")
		)
		(zone
			(layer "B.Cu")
			(hatch none 0.5)
			(connect_pads
				(clearance 0)
			)
			(min_thickness 0.25)
			(keepout
				(tracks allowed)
				(vias not_allowed)
				(pads allowed)
				(copperpour not_allowed)
				(footprints allowed)
			)
			(placement
				(enabled no)
				(sheetname "")
			)
			(fill
				(thermal_gap 0.5)
				(thermal_bridge_width 0.5)
				(island_removal_mode 0)
			)
			(polygon
				(pts
					(xy 387.858 -16.637) (xy 387.858 -16.129) (xy 388.239 -16.129) (xy 388.239 -16.637)
				)
			)
		)
		(zone
			(layer "B.Cu")
			(hatch none 0.5)
			(connect_pads
				(clearance 0)
			)
			(min_thickness 0.25)
			(keepout
				(tracks not_allowed)
				(vias allowed)
				(pads allowed)
				(copperpour not_allowed)
				(footprints allowed)
			)
			(placement
				(enabled no)
				(sheetname "")
			)
			(fill
				(thermal_gap 0.5)
				(thermal_bridge_width 0.5)
				(island_removal_mode 0)
			)
			(polygon
				(pts
					(xy 388.239 -16.637) (xy 388.239 -16.129) (xy 387.858 -16.129) (xy 387.858 -16.637)
				)
			)
		)
	)
	(footprint ""
		(layer "B.Cu")
		(at 369.145058 -77.096112 90)
		(property "Reference" "C3P48"
			(at 0 0 90)
			(layer "B.SilkS")
			(hide yes)
			(effects
				(font
					(size 1.27 1.27)
				)
				(justify mirror)
			)
		)
		(property "Value" ""
			(at 0 0 90)
			(layer "B.Fab")
			(effects
				(font
					(size 1.27 1.27)
				)
				(justify mirror)
			)
		)
		(duplicate_pad_numbers_are_jumpers no)
		(fp_rect
			(start 0.2794 0.9144)
			(end -0.2794 -0.1143)
			(stroke
				(width 0)
				(type default)
			)
			(fill no)
			(layer "B.CrtYd")
		)
		(fp_line
			(start 0.2794 -0.1143)
			(end -0.2794 -0.1143)
			(stroke
				(width 0.1)
				(type default)
			)
			(layer "B.Fab")
		)
		(fp_line
			(start -0.2794 -0.1143)
			(end -0.2794 0.9144)
			(stroke
				(width 0.1)
				(type default)
			)
			(layer "B.Fab")
		)
		(fp_line
			(start 0.2794 0.9144)
			(end 0.2794 -0.1143)
			(stroke
				(width 0.1)
				(type default)
			)
			(layer "B.Fab")
		)
		(fp_line
			(start -0.2794 0.9144)
			(end 0.2794 0.9144)
			(stroke
				(width 0.1)
				(type default)
			)
			(layer "B.Fab")
		)
		(pad "1" smd custom
			(at 0 0)
			(size 0.10414 0.10414)
			(layers "B.Cu" "B.Mask" "B.Paste")
			(net "P3V3_STBY")
			(options
				(clearance outline)
				(anchor circle)
			)
			(primitives
				(gr_poly
					(pts
						(xy -0.20828 -0.08636) (xy -0.20828 0.08636) (xy -0.08636 0.20828) (xy 0.086614 0.20828) (xy 0.20828 0.086614)
						(xy 0.20828 -0.08636) (xy 0.08636 -0.20828) (xy -0.08636 -0.20828)
					)
					(width 0)
					(fill yes)
				)
			)
		)
		(pad "2" smd custom
			(at 0 0.8001)
			(size 0.10414 0.10414)
			(layers "B.Cu" "B.Mask" "B.Paste")
			(net "GND")
			(options
				(clearance outline)
				(anchor circle)
			)
			(primitives
				(gr_poly
					(pts
						(xy -0.20828 -0.08636) (xy -0.20828 0.08636) (xy -0.08636 0.20828) (xy 0.086614 0.20828) (xy 0.20828 0.086614)
						(xy 0.20828 -0.08636) (xy 0.08636 -0.20828) (xy -0.08636 -0.20828)
					)
					(width 0)
					(fill yes)
				)
			)
		)
		(zone
			(layer "B.Cu")
			(hatch none 0.5)
			(connect_pads
				(clearance 0)
			)
			(min_thickness 0.25)
			(keepout
				(tracks allowed)
				(vias not_allowed)
				(pads allowed)
				(copperpour not_allowed)
				(footprints allowed)
			)
			(placement
				(enabled no)
				(sheetname "")
			)
			(fill
				(thermal_gap 0.5)
				(thermal_bridge_width 0.5)
				(island_removal_mode 0)
			)
			(polygon
				(pts
					(xy 369.354608 -77.183742) (xy 369.735608 -77.183742) (xy 369.735608 -77.008482) (xy 369.354608 -77.008228)
				)
			)
		)
		(zone
			(layer "B.Cu")
			(hatch none 0.5)
			(connect_pads
				(clearance 0)
			)
			(min_thickness 0.25)
			(keepout
				(tracks not_allowed)
				(vias allowed)
				(pads allowed)
				(copperpour not_allowed)
				(footprints allowed)
			)
			(placement
				(enabled no)
				(sheetname "")
			)
			(fill
				(thermal_gap 0.5)
				(thermal_bridge_width 0.5)
				(island_removal_mode 0)
			)
			(polygon
				(pts
					(xy 369.354608 -77.183742) (xy 369.735608 -77.183742) (xy 369.735608 -77.008482) (xy 369.354608 -77.008228)
				)
			)
		)
	)
	(footprint ""
		(layer "B.Cu")
		(at 155.293568 -135.376412 90)
		(property "Reference" "C7M3"
			(at 0 0 90)
			(layer "B.SilkS")
			(hide yes)
			(effects
				(font
					(size 1.27 1.27)
				)
				(justify mirror)
			)
		)
		(property "Value" ""
			(at 0 0 90)
			(layer "B.Fab")
			(effects
				(font
					(size 1.27 1.27)
				)
				(justify mirror)
			)
		)
		(duplicate_pad_numbers_are_jumpers no)
		(fp_rect
			(start 0.4953 1.6002)
			(end -0.4953 -0.2032)
			(stroke
				(width 0)
				(type default)
			)
			(fill no)
			(layer "B.CrtYd")
		)
		(fp_line
			(start 0.4953 -0.2032)
			(end -0.4953 -0.2032)
			(stroke
				(width 0.1)
				(type default)
			)
			(layer "B.Fab")
		)
		(fp_line
			(start -0.4953 -0.2032)
			(end -0.4953 1.6002)
			(stroke
				(width 0.1)
				(type default)
			)
			(layer "B.Fab")
		)
		(fp_line
			(start 0.4953 1.6002)
			(end 0.4953 -0.2032)
			(stroke
				(width 0.1)
				(type default)
			)
			(layer "B.Fab")
		)
		(fp_line
			(start -0.4953 1.6002)
			(end 0.4953 1.6002)
			(stroke
				(width 0.1)
				(type default)
			)
			(layer "B.Fab")
		)
		(pad "1" smd rect
			(at 0 0 270)
			(size 0.762 0.889)
			(layers "B.Cu" "B.Mask" "B.Paste")
			(net "PVPP_KLM")
		)
		(pad "2" smd rect
			(at 0 1.397 270)
			(size 0.762 0.889)
			(layers "B.Cu" "B.Mask" "B.Paste")
			(net "GND")
		)
		(zone
			(layer "B.Cu")
			(hatch none 0.5)
			(connect_pads
				(clearance 0)
			)
			(min_thickness 0.25)
			(keepout
				(tracks not_allowed)
				(vias allowed)
				(pads allowed)
				(copperpour not_allowed)
				(footprints allowed)
			)
			(placement
				(enabled no)
				(sheetname "")
			)
			(fill
				(thermal_gap 0.5)
				(thermal_bridge_width 0.5)
				(island_removal_mode 0)
			)
			(polygon
				(pts
					(xy 156.246068 -135.757412) (xy 155.738068 -135.757412) (xy 155.738068 -134.995412) (xy 156.246068 -134.995412)
				)
			)
		)
	)
)
